FILE_TYPE=LIBRARY_PARTS;
TIME=' Created/Modified on Fri Mar 27 13:23:37 2009' ;
primitive 'Q_FUSE';
  pin
    '1':
      PIN_NUMBER='(1)';
      INPUT_LOAD='(-0.01,0.01)';
      OUTPUT_LOAD='(1.0,-1.0)';
      BIDIRECTIONAL='TRUE';
    '2':
      PIN_NUMBER='(2)';
      INPUT_LOAD='(-0.01,0.01)';
      OUTPUT_LOAD='(1.0,-1.0)';
      BIDIRECTIONAL='TRUE';
  end_pin;
  body
    CLASS='DISCRETE';
    PART_NAME='Q_FUSE';
    PHYS_DES_PREFIX='FS';
  end_body;
end_primitive;
END.
